(kicad_pcb
	(version 20260206)
	(generator "pcbnew")
	(generator_version "10.0")
	(general
		(thickness 1.6)
		(legacy_teardrops no)
	)
	(paper "A4")
	(title_block
		(title "Bryce Canyon_R.DPB_16317-1_OCP.brd")
		(comment 1 "Bryce Canyon / footprints 839-842 of 2099")
	)
	(layers
		(0 "F.Cu" signal "TOP")
		(4 "In1.Cu" signal "L2GND")
		(6 "In2.Cu" signal "L3")
		(8 "In3.Cu" signal "L4VCC")
		(10 "In4.Cu" signal "L5VCC")
		(12 "In5.Cu" signal "L6")
		(14 "In6.Cu" signal "L7GND")
		(2 "B.Cu" signal "BOTTOM")
		(9 "F.Adhes" user "F.Adhesive")
		(11 "B.Adhes" user "B.Adhesive")
		(13 "F.Paste" user "Package Geometry/Pastemask Top")
		(15 "B.Paste" user "Package Geometry/Pastemask Bottom")
		(5 "F.SilkS" user "Ref Des/Silkscreen Top")
		(7 "B.SilkS" user "Ref Des/Silkscreen Bottom")
		(1 "F.Mask" user "Board Geometry/Soldermask Top")
		(3 "B.Mask" user "Board Geometry/Soldermask Bottom")
		(17 "Dwgs.User" user "User.Drawings")
		(19 "Cmts.User" user "User.Comments")
		(21 "Eco1.User" user "User.Eco1")
		(23 "Eco2.User" user "User.Eco2")
		(25 "Edge.Cuts" user "Board Geometry/Outline")
		(27 "Margin" user)
		(31 "F.CrtYd" user "Package Geometry/Place Bound Top")
		(29 "B.CrtYd" user "Package Geometry/Place Bound Bottom")
		(35 "F.Fab" user "Ref Des/Assembly Top")
		(33 "B.Fab" user "Ref Des/Assembly Bottom")
	)
	(footprint ""
		(layer "F.Cu")
		(at 463.042 -246.761 180)
		(property "Reference" "R328"
			(at 0 0 180)
			(layer "F.SilkS")
			(hide yes)
			(effects
				(font
					(size 1.27 1.27)
				)
			)
		)
		(property "Value" "4K7R2J-2-GP"
			(at 0.064008 -3.993896 180)
			(unlocked yes)
			(layer "F.Fab")
			(hide yes)
			(effects
				(font
					(size 1.016 1.016)
					(thickness 0.1524)
				)
			)
		)
		(property "Device Type" "R402H16"
			(at 0.064008 -5.517896 180)
			(unlocked yes)
			(layer "F.Fab")
			(hide yes)
			(effects
				(font
					(size 1.016 1.016)
					(thickness 0.1524)
				)
			)
		)
		(duplicate_pad_numbers_are_jumpers no)
		(fp_line
			(start 0.508 -0.9398)
			(end -0.508 -0.9398)
			(stroke
				(width 0.1524)
				(type default)
			)
			(layer "F.SilkS")
		)
		(fp_line
			(start -0.508 -0.9398)
			(end -0.508 0.9398)
			(stroke
				(width 0.1524)
				(type default)
			)
			(layer "F.SilkS")
		)
		(fp_rect
			(start -0.508 0.9398)
			(end 0.508 -0.9398)
			(stroke
				(width 0)
				(type default)
			)
			(fill no)
			(layer "F.CrtYd")
		)
		(fp_rect
			(start -0.508 0.9398)
			(end 0.508 -0.9398)
			(stroke
				(width 0)
				(type default)
			)
			(fill no)
			(layer "F.Fab")
		)
		(pad "1" smd custom
			(at 0 -0.4445 180)
			(size 0.1397 0.1397)
			(layers "F.Cu" "F.Mask" "F.Paste")
			(net "P12V_B")
			(options
				(clearance outline)
				(anchor circle)
			)
			(primitives
				(gr_poly
					(pts
						(arc
							(start -0.1778 -0.2794)
							(mid -0.249642 -0.249642)
							(end -0.2794 -0.1778)
						)
						(arc
							(start -0.2794 0.1778)
							(mid -0.249642 0.249642)
							(end -0.1778 0.2794)
						)
						(arc
							(start 0.1778 0.2794)
							(mid 0.249642 0.249642)
							(end 0.2794 0.1778)
						)
						(arc
							(start 0.2794 -0.1778)
							(mid 0.249642 -0.249642)
							(end 0.1778 -0.2794)
						)
					)
					(width 0)
					(fill yes)
				)
			)
		)
		(pad "2" smd custom
			(at 0 0.4445 180)
			(size 0.1397 0.1397)
			(layers "F.Cu" "F.Mask" "F.Paste")
			(net "SW_HDD_R10")
			(options
				(clearance outline)
				(anchor circle)
			)
			(primitives
				(gr_poly
					(pts
						(arc
							(start -0.1778 -0.2794)
							(mid -0.249642 -0.249642)
							(end -0.2794 -0.1778)
						)
						(arc
							(start -0.2794 0.1778)
							(mid -0.249642 0.249642)
							(end -0.1778 0.2794)
						)
						(arc
							(start 0.1778 0.2794)
							(mid 0.249642 0.249642)
							(end 0.2794 0.1778)
						)
						(arc
							(start 0.2794 -0.1778)
							(mid 0.249642 -0.249642)
							(end 0.1778 -0.2794)
						)
					)
					(width 0)
					(fill yes)
				)
			)
		)
	)
	(footprint ""
		(layer "F.Cu")
		(at 475.742 -256.286 180)
		(property "Reference" "Q42"
			(at 0 0 180)
			(layer "F.SilkS")
			(hide yes)
			(effects
				(font
					(size 1.27 1.27)
				)
			)
		)
		(property "Value" "AO4406AL-GP"
			(at -3.707384 -1.5367 180)
			(unlocked yes)
			(layer "F.Fab")
			(hide yes)
			(effects
				(font
					(size 1.016 1.016)
					(thickness 0.1524)
				)
			)
		)
		(property "Device Type" "SOIC8H69"
			(at -3.707384 -3.0607 180)
			(unlocked yes)
			(layer "F.Fab")
			(hide yes)
			(effects
				(font
					(size 1.016 1.016)
					(thickness 0.1524)
				)
			)
		)
		(duplicate_pad_numbers_are_jumpers no)
		(fp_line
			(start 2.1336 1.4224)
			(end 2.1336 -1.4224)
			(stroke
				(width 0.1524)
				(type default)
			)
			(layer "F.SilkS")
		)
		(fp_line
			(start 2.1336 -1.4224)
			(end -2.7432 -1.4224)
			(stroke
				(width 0.1524)
				(type default)
			)
			(layer "F.SilkS")
		)
		(fp_line
			(start -2.1844 -0.0508)
			(end -2.7178 0.508)
			(stroke
				(width 0.1524)
				(type default)
			)
			(layer "F.SilkS")
		)
		(fp_line
			(start -2.6289 3.4417)
			(end -2.6289 1.4732)
			(stroke
				(width 0.381)
				(type default)
			)
			(layer "F.SilkS")
		)
		(fp_line
			(start -2.7178 -0.508)
			(end -2.1844 -0.0508)
			(stroke
				(width 0.1524)
				(type default)
			)
			(layer "F.SilkS")
		)
		(fp_line
			(start -2.7432 1.4224)
			(end 2.1336 1.4224)
			(stroke
				(width 0.1524)
				(type default)
			)
			(layer "F.SilkS")
		)
		(fp_line
			(start -2.7432 1.4224)
			(end -2.6416 1.4224)
			(stroke
				(width 0.1524)
				(type default)
			)
			(layer "F.SilkS")
		)
		(fp_line
			(start -2.7432 -1.4224)
			(end -2.7432 1.4224)
			(stroke
				(width 0.1524)
				(type default)
			)
			(layer "F.SilkS")
		)
		(fp_poly
			(pts
				(xy -2.2098 -1.4224) (xy -2.2098 1.4224) (xy 2.2098 1.4224) (xy 2.2098 -1.4224)
			)
			(stroke
				(width 0)
				(type default)
			)
			(fill yes)
			(layer "F.SilkS")
		)
		(fp_rect
			(start -2.450084 2.999994)
			(end 2.450084 -2.999994)
			(stroke
				(width 0)
				(type default)
			)
			(fill no)
			(layer "F.CrtYd")
		)
		(fp_poly
			(pts
				(xy -2.8194 3.6322) (xy -2.8194 -3.6322) (xy 2.8194 -3.6322) (xy 2.8194 1.18364) (xy 2.450084 1.18364)
				(xy 2.450084 -2.999994) (xy -2.450084 -2.999994) (xy -2.450084 2.999994) (xy 2.450084 2.999994)
				(xy 2.450084 1.18618) (xy 2.8194 1.18618) (xy 2.8194 3.6322)
			)
			(stroke
				(width 0)
				(type default)
			)
			(fill no)
			(layer "F.CrtYd")
		)
		(fp_rect
			(start -2.8194 3.6322)
			(end 2.8194 -3.6322)
			(stroke
				(width 0)
				(type default)
			)
			(fill no)
			(layer "F.Fab")
		)
		(pad "1" smd rect
			(at -1.905 2.54 180)
			(size 0.635 1.651)
			(layers "F.Cu" "F.Mask" "F.Paste")
			(net "P5V_HDD11")
		)
		(pad "2" smd rect
			(at -0.635 2.54 180)
			(size 0.635 1.651)
			(layers "F.Cu" "F.Mask" "F.Paste")
			(net "P5V_HDD11")
		)
		(pad "3" smd rect
			(at 0.635 2.54 180)
			(size 0.635 1.651)
			(layers "F.Cu" "F.Mask" "F.Paste")
			(net "P5V_HDD11")
		)
		(pad "4" smd rect
			(at 1.905 2.54 180)
			(size 0.635 1.651)
			(layers "F.Cu" "F.Mask" "F.Paste")
			(net "SW_HDD_P11")
		)
		(pad "5" smd rect
			(at 1.905 -2.54 180)
			(size 0.635 1.651)
			(layers "F.Cu" "F.Mask" "F.Paste")
			(net "P5V_B_3")
		)
		(pad "6" smd rect
			(at 0.635 -2.54 180)
			(size 0.635 1.651)
			(layers "F.Cu" "F.Mask" "F.Paste")
			(net "P5V_B_3")
		)
		(pad "7" smd rect
			(at -0.635 -2.54 180)
			(size 0.635 1.651)
			(layers "F.Cu" "F.Mask" "F.Paste")
			(net "P5V_B_3")
		)
		(pad "8" smd rect
			(at -1.905 -2.54 180)
			(size 0.635 1.651)
			(layers "F.Cu" "F.Mask" "F.Paste")
			(net "P5V_B_3")
		)
	)
	(footprint ""
		(layer "F.Cu")
		(at 247.15978 -211.690712)
		(property "Reference" "R110"
			(at 0 0 0)
			(layer "F.SilkS")
			(hide yes)
			(effects
				(font
					(size 1.27 1.27)
				)
			)
		)
		(property "Value" "0R2J-2-GP"
			(at 0.064008 -3.993896 0)
			(unlocked yes)
			(layer "F.Fab")
			(hide yes)
			(effects
				(font
					(size 1.016 1.016)
					(thickness 0.1524)
				)
			)
		)
		(property "Device Type" "R402H16"
			(at 0.064008 -5.517896 0)
			(unlocked yes)
			(layer "F.Fab")
			(hide yes)
			(effects
				(font
					(size 1.016 1.016)
					(thickness 0.1524)
				)
			)
		)
		(duplicate_pad_numbers_are_jumpers no)
		(fp_line
			(start -0.508 -0.9398)
			(end -0.508 0.9398)
			(stroke
				(width 0.1524)
				(type default)
			)
			(layer "F.SilkS")
		)
		(fp_line
			(start 0.508 -0.9398)
			(end -0.508 -0.9398)
			(stroke
				(width 0.1524)
				(type default)
			)
			(layer "F.SilkS")
		)
		(fp_rect
			(start -0.508 0.9398)
			(end 0.508 -0.9398)
			(stroke
				(width 0)
				(type default)
			)
			(fill no)
			(layer "F.CrtYd")
		)
		(fp_rect
			(start -0.508 0.9398)
			(end 0.508 -0.9398)
			(stroke
				(width 0)
				(type default)
			)
			(fill no)
			(layer "F.Fab")
		)
		(pad "1" smd custom
			(at 0 -0.4445)
			(size 0.1397 0.1397)
			(layers "F.Cu" "F.Mask" "F.Paste")
			(net "EEPROM_SDA")
			(options
				(clearance outline)
				(anchor circle)
			)
			(primitives
				(gr_poly
					(pts
						(arc
							(start -0.1778 -0.2794)
							(mid -0.249642 -0.249642)
							(end -0.2794 -0.1778)
						)
						(arc
							(start -0.2794 0.1778)
							(mid -0.249642 0.249642)
							(end -0.1778 0.2794)
						)
						(arc
							(start 0.1778 0.2794)
							(mid 0.249642 0.249642)
							(end 0.2794 0.1778)
						)
						(arc
							(start 0.2794 -0.1778)
							(mid 0.249642 -0.249642)
							(end 0.1778 -0.2794)
						)
					)
					(width 0)
					(fill yes)
				)
			)
		)
		(pad "2" smd custom
			(at 0 0.4445)
			(size 0.1397 0.1397)
			(layers "F.Cu" "F.Mask" "F.Paste")
			(net "I2C_DPB_B_SDA_BUF")
			(options
				(clearance outline)
				(anchor circle)
			)
			(primitives
				(gr_poly
					(pts
						(arc
							(start -0.1778 -0.2794)
							(mid -0.249642 -0.249642)
							(end -0.2794 -0.1778)
						)
						(arc
							(start -0.2794 0.1778)
							(mid -0.249642 0.249642)
							(end -0.1778 0.2794)
						)
						(arc
							(start 0.1778 0.2794)
							(mid 0.249642 0.249642)
							(end 0.2794 0.1778)
						)
						(arc
							(start 0.2794 -0.1778)
							(mid 0.249642 -0.249642)
							(end 0.1778 -0.2794)
						)
					)
					(width 0)
					(fill yes)
				)
			)
		)
	)
	(footprint ""
		(layer "F.Cu")
		(at 20.447 -249.555 180)
		(property "Reference" "Q191"
			(at 0 0 180)
			(layer "F.SilkS")
			(hide yes)
			(effects
				(font
					(size 1.27 1.27)
				)
			)
		)
		(property "Value" "2N7002KDW-GP"
			(at -2.3622 -8.2042 180)
			(unlocked yes)
			(layer "F.Fab")
			(hide yes)
			(effects
				(font
					(size 1.016 1.016)
					(thickness 0.1524)
				)
			)
		)
		(property "Device Type" "SOT-363H44"
			(at -2.3622 -10.1092 180)
			(unlocked yes)
			(layer "F.Fab")
			(hide yes)
			(effects
				(font
					(size 1.016 1.016)
					(thickness 0.1524)
				)
			)
		)
		(duplicate_pad_numbers_are_jumpers no)
		(fp_line
			(start 1.4478 1.7018)
			(end 1.4478 -1.7018)
			(stroke
				(width 0.1524)
				(type default)
			)
			(layer "F.SilkS")
		)
		(fp_line
			(start 1.4478 -1.7018)
			(end -1.4478 -1.7018)
			(stroke
				(width 0.1524)
				(type default)
			)
			(layer "F.SilkS")
		)
		(fp_line
			(start -1.27 1.524)
			(end -1.27 0.6604)
			(stroke
				(width 0.4826)
				(type default)
			)
			(layer "F.SilkS")
		)
		(fp_line
			(start -1.4478 1.7018)
			(end 1.4478 1.7018)
			(stroke
				(width 0.1524)
				(type default)
			)
			(layer "F.SilkS")
		)
		(fp_line
			(start -1.4478 -1.7018)
			(end -1.4478 1.7018)
			(stroke
				(width 0.1524)
				(type default)
			)
			(layer "F.SilkS")
		)
		(fp_poly
			(pts
				(xy -1.524 -1.778) (xy 1.524 -1.778) (xy 1.524 1.778) (xy -1.524 1.778)
			)
			(stroke
				(width 0)
				(type default)
			)
			(fill no)
			(layer "F.CrtYd")
		)
		(fp_poly
			(pts
				(xy -1.524 -1.778) (xy 1.524 -1.778) (xy 1.524 1.778) (xy -1.524 1.778)
			)
			(stroke
				(width 0)
				(type default)
			)
			(fill no)
			(layer "F.Fab")
		)
		(pad "1" smd rect
			(at -0.65024 0.9398 180)
			(size 0.4064 1.016)
			(layers "F.Cu" "F.Mask" "F.Paste")
			(net "GND")
		)
		(pad "2" smd rect
			(at 0 0.9398 180)
			(size 0.4064 1.016)
			(layers "F.Cu" "F.Mask" "F.Paste")
			(net "SW_PWR_R_HDD0")
		)
		(pad "3" smd rect
			(at 0.65024 0.9398 180)
			(size 0.4064 1.016)
			(layers "F.Cu" "F.Mask" "F.Paste")
			(net "SW_HDD_P0")
		)
		(pad "4" smd rect
			(at 0.65024 -0.9398 180)
			(size 0.4064 1.016)
			(layers "F.Cu" "F.Mask" "F.Paste")
			(net "GND")
		)
		(pad "5" smd rect
			(at 0 -0.9398 180)
			(size 0.4064 1.016)
			(layers "F.Cu" "F.Mask" "F.Paste")
			(net "SW_HDD_G0")
		)
		(pad "6" smd rect
			(at -0.65024 -0.9398 180)
			(size 0.4064 1.016)
			(layers "F.Cu" "F.Mask" "F.Paste")
			(net "SW_HDD_R0")
		)
	)
)
